# Lightning_PDPB_EQL.xlsx — PCIE_RX_1027 (si-constraints)
|  |  | Group | Pin | NET1 | NET2 | NET3 | NET4 | NET5 | Length (NET1) | <1mils  match (NET1) | Length (NET2) | <1mils  match (NET2) | Length (NET3) | <1mils  match (NET3) | Length (NET4) | <1mils  match (NET4) | Length (NET5) | <1mils  match (NET5) | Unnecessary trace | Total Length | mils Bundle Length match | <1mils  Total Length match | <2000mils  Pair to pair Length match | Note |
|  |  | 1_J17 | B7 | PE_RX1_DR1_n |  |  |  |  | 9224.75 | OK |  | OK |  | OK |  | OK |  | OK |  | 9224.75 | OK | OK | OK |  |
|  |  |  | B8 | PE_RX1_DR1_p |  |  |  |  | 9224.4699999999993 |  |  |  |  |  |  |  |  |  |  | 9224.4699999999993 |  |  |  |  |
|  |  |  | B11 | PE_RX2_DR1_n |  |  |  |  | 9035.0400000000009 | OK |  | OK |  | OK |  | OK |  | OK |  | 9035.0400000000009 |  | OK |  |  |
|  |  |  | B12 | PE_RX2_DR1_p |  |  |  |  | 9034.94 |  |  |  |  |  |  |  |  |  |  | 9034.94 |  |  |  |  |
| DPB SPEC |  |  | B15 | PE_RX3_DR1_n |  |  |  |  | 9000.83 | OK |  | OK |  | OK |  | OK |  | OK |  | 9000.83 | OK | OK |  |  |
| PCIE max length | 16inch |  | B16 | PE_RX3_DR1_p |  |  |  |  | 9000.7999999999993 |  |  |  |  |  |  |  |  |  |  | 9000.7999999999993 |  |  |  |  |
| +/- match (Segment) NET1 | 1mil |  | B19 | PE_RX4_DR1_n |  |  |  |  | 8966.26 | OK |  | OK |  | OK |  | OK |  | OK |  | 8966.26 |  | OK |  |  |
| +/- match (Segment) NET2 | 1mil |  | B20 | PE_RX4_DR1_p |  |  |  |  | 8966.25 |  |  |  |  |  |  |  |  |  |  | 8966.25 |  |  |  |  |
|  |  |  | B26 | PE_RX1_DR10_p |  |  |  |  | 3596.5 | OK |  | OK |  | OK |  | OK |  | OK |  | 3596.5 | OK | OK | OK |  |
|  |  |  | B27 | PE_RX1_DR10_n |  |  |  |  | 3595.8 |  |  |  |  |  |  |  |  |  |  | 3595.8 |  |  |  |  |
|  |  |  | B30 | PE_RX2_DR10_p |  |  |  |  | 3115.67 | OK |  | OK |  | OK |  | OK |  | OK |  | 3115.67 |  | OK |  |  |
|  |  |  | B31 | PE_RX2_DR10_n |  |  |  |  | 3114.96 |  |  |  |  |  |  |  |  |  |  | 3114.96 |  |  |  |  |
|  |  |  | B34 | PE_RX3_DR10_p |  |  |  |  | 2852.88 | OK |  | OK |  | OK |  | OK |  | OK |  | 2852.88 | OK | OK |  |  |
|  |  |  | B35 | PE_RX3_DR10_n |  |  |  |  | 2852.29 |  |  |  |  |  |  |  |  |  |  | 2852.29 |  |  |  |  |
|  |  |  | B38 | PE_RX4_DR10_p |  |  |  |  | 2675.78 | OK |  | OK |  | OK |  | OK |  | OK |  | 2675.78 |  | OK |  |  |
|  |  |  | B39 | PE_RX4_DR10_n |  |  |  |  | 2675.15 |  |  |  |  |  |  |  |  |  |  | 2675.15 |  |  |  |  |
|  |  |  | B42 | PE_RX1_DR0_n |  |  |  |  | 10182.700000000001 | OK |  | OK |  | OK |  | OK |  | OK |  | 10182.700000000001 | OK | OK | OK |  |
|  |  |  | B43 | PE_RX1_DR0_p |  |  |  |  | 10182.27 |  |  |  |  |  |  |  |  |  |  | 10182.27 |  |  |  |  |
|  |  |  | B46 | PE_RX2_DR0_n |  |  |  |  | 10157.67 | OK |  | OK |  | OK |  | OK |  | OK |  | 10157.67 |  | OK |  |  |
|  |  |  | B47 | PE_RX2_DR0_p |  |  |  |  | 10157.14 |  |  |  |  |  |  |  |  |  |  | 10157.14 |  |  |  |  |
|  |  |  | B50 | PE_RX3_DR0_n |  |  |  |  | 10292.31 | OK |  | OK |  | OK |  | OK |  | OK |  | 10292.31 | OK | OK |  |  |
|  |  |  | B51 | PE_RX3_DR0_p |  |  |  |  | 10292.31 |  |  |  |  |  |  |  |  |  |  | 10292.31 |  |  |  |  |
|  |  |  | B54 | PE_RX4_DR0_n |  |  |  |  | 10467.57 | OK |  | OK |  | OK |  | OK |  | OK |  | 10467.57 |  | OK |  |  |
|  |  |  | B55 | PE_RX4_DR0_p |  |  |  |  | 10467.49 |  |  |  |  |  |  |  |  |  |  | 10467.49 |  |  |  |  |
|  |  |  | B61 | PE_RX1_DR5_p |  |  |  |  | 2407.2199999999998 | OK |  | OK |  | OK |  | OK |  | OK |  | 2407.2199999999998 | OK | OK | OK |  |
|  |  |  | B62 | PE_RX1_DR5_n |  |  |  |  | 2407.0500000000002 |  |  |  |  |  |  |  |  |  |  | 2407.0500000000002 |  |  |  |  |
|  |  |  | B65 | PE_RX2_DR5_p |  |  |  |  | 2694.57 | OK |  | OK |  | OK |  | OK |  | OK |  | 2694.57 |  | OK |  |  |
|  |  |  | B66 | PE_RX2_DR5_n |  |  |  |  | 2694.53 |  |  |  |  |  |  |  |  |  |  | 2694.53 |  |  |  |  |
|  |  |  | B69 | PE_RX3_DR5_p |  |  |  |  | 2707.31 | OK |  | OK |  | OK |  | OK |  | OK |  | 2707.31 | OK | OK |  |  |
|  |  |  | B70 | PE_RX3_DR5_n |  |  |  |  | 2707.26 |  |  |  |  |  |  |  |  |  |  | 2707.26 |  |  |  |  |
|  |  |  | B73 | PE_RX4_DR5_p |  |  |  |  | 2727.8 | OK |  | OK |  | OK |  | OK |  | OK |  | 2727.8 |  | OK |  |  |
|  |  |  | B74 | PE_RX4_DR5_n |  |  |  |  | 2727.81 |  |  |  |  |  |  |  |  |  |  | 2727.81 |  |  |  |  |
|  |  | 2_J18 | B4 | PE_RX3_DR4_n |  |  |  |  | 12497.44 | OK |  | OK |  | OK |  | OK |  | OK |  | 12497.44 | OK | OK | OK |  |
|  |  |  | B5 | PE_RX3_DR4_p |  |  |  |  | 12497.42 |  |  |  |  |  |  |  |  |  |  | 12497.42 |  |  |  |  |
|  |  |  | B8 | PE_RX4_DR4_n |  |  |  |  | 12502.67 | OK |  | OK |  | OK |  | OK |  | OK |  | 12502.67 |  | OK |  |  |
|  |  |  | B9 | PE_RX4_DR4_p |  |  |  |  | 12502.65 |  |  |  |  |  |  |  |  |  |  | 12502.65 |  |  |  |  |
|  |  |  | B16 | PE_RX1_DR3_n |  |  |  |  | 11078.47 | OK |  | OK |  | OK |  | OK |  | OK |  | 11078.47 | OK | OK | OK |  |
|  |  |  | B17 | PE_RX1_DR3_p |  |  |  |  | 11078.3 |  |  |  |  |  |  |  |  |  |  | 11078.3 |  |  |  |  |
|  |  |  | B20 | PE_RX2_DR3_n |  |  |  |  | 11056.54 | OK |  | OK |  | OK |  | OK |  | OK |  | 11056.54 |  | OK |  |  |
|  |  |  | B21 | PE_RX2_DR3_p |  |  |  |  | 11056.53 |  |  |  |  |  |  |  |  |  |  | 11056.53 |  |  |  |  |
|  |  |  | B24 | PE_RX3_DR3_n |  |  |  |  | 11107.93 | OK |  | OK |  | OK |  | OK |  | OK |  | 11107.93 | OK | OK |  |  |
|  |  |  | B25 | PE_RX3_DR3_p |  |  |  |  | 11107.92 |  |  |  |  |  |  |  |  |  |  | 11107.92 |  |  |  |  |
|  |  |  | B28 | PE_RX4_DR3_n |  |  |  |  | 11132.52 | OK |  | OK |  | OK |  | OK |  | OK |  | 11132.52 |  | OK |  |  |
|  |  |  | B29 | PE_RX4_DR3_p |  |  |  |  | 11132.46 |  |  |  |  |  |  |  |  |  |  | 11132.46 |  |  |  |  |
|  |  |  | B32 | PE_RX1_DR7_n |  |  |  |  | 2396.08 | OK |  | OK |  | OK |  | OK |  | OK |  | 2396.08 | OK | OK | OK |  |
|  |  |  | B33 | PE_RX1_DR7_p |  |  |  |  | 2396.08 |  |  |  |  |  |  |  |  |  |  | 2396.08 |  |  |  |  |
|  |  |  | B36 | PE_RX2_DR7_n |  |  |  |  | 2068.34 | OK |  | OK |  | OK |  | OK |  | OK |  | 2068.34 |  | OK |  |  |
|  |  |  | B37 | PE_RX2_DR7_p |  |  |  |  | 2068.3200000000002 |  |  |  |  |  |  |  |  |  |  | 2068.3200000000002 |  |  |  |  |
|  |  |  | B40 | PE_RX3_DR7_n |  |  |  |  | 2013.83 | OK |  | OK |  | OK |  | OK |  | OK |  | 2013.83 | OK | OK |  |  |
|  |  |  | B41 | PE_RX3_DR7_p |  |  |  |  | 2013.8 |  |  |  |  |  |  |  |  |  |  | 2013.8 |  |  |  |  |
|  |  |  | B46 | PE_RX4_DR7_n |  |  |  |  | 2166.6799999999998 | OK |  | OK |  | OK |  | OK |  | OK |  | 2166.6799999999998 |  | OK |  |  |
|  |  |  | B47 | PE_RX4_DR7_p |  |  |  |  | 2166.69 |  |  |  |  |  |  |  |  |  |  | 2166.69 |  |  |  |  |
|  |  |  | B50 | PE_RX1_DR2_n |  |  |  |  | 9545.4699999999993 | OK |  | OK |  | OK |  | OK |  | OK |  | 9545.4699999999993 | OK | OK | OK |  |
|  |  |  | B51 | PE_RX1_DR2_p |  |  |  |  | 9545.43 |  |  |  |  |  |  |  |  |  |  | 9545.43 |  |  |  |  |
|  |  |  | B54 | PE_RX2_DR2_n |  |  |  |  | 9618.1200000000008 | OK |  | OK |  | OK |  | OK |  | OK |  | 9618.1200000000008 |  | OK |  |  |
|  |  |  | B55 | PE_RX2_DR2_p |  |  |  |  | 9618.0300000000007 |  |  |  |  |  |  |  |  |  |  | 9618.0300000000007 |  |  |  |  |
|  |  |  | B58 | PE_RX3_DR2_n |  |  |  |  | 9702.44 | OK |  | OK |  | OK |  | OK |  | OK |  | 9702.44 | OK | OK |  |  |
|  |  |  | B59 | PE_RX3_DR2_p |  |  |  |  | 9702.3799999999992 |  |  |  |  |  |  |  |  |  |  | 9702.3799999999992 |  |  |  |  |
|  |  |  | B62 | PE_RX4_DR2_n |  |  |  |  | 9760.4599999999991 | OK |  | OK |  | OK |  | OK |  | OK |  | 9760.4599999999991 |  | OK |  |  |
|  |  |  | B63 | PE_RX4_DR2_p |  |  |  |  | 9760.4 |  |  |  |  |  |  |  |  |  |  | 9760.4 |  |  |  |  |
|  |  |  | B69 | PE_RX1_DR11_n |  |  |  |  | 1362.03 | OK |  | OK |  | OK |  | OK |  | OK |  | 1362.03 | OK | OK | OK |  |
|  |  |  | B70 | PE_RX1_DR11_p |  |  |  |  | 1361.43 |  |  |  |  |  |  |  |  |  |  | 1361.43 |  |  |  |  |
|  |  |  | B73 | PE_RX2_DR11_n |  |  |  |  | 2302.9699999999998 | OK |  | OK |  | OK |  | OK |  | OK |  | 2302.9699999999998 |  | OK |  |  |
|  |  |  | B74 | PE_RX2_DR11_p |  |  |  |  | 2303.58 |  |  |  |  |  |  |  |  |  |  | 2303.58 |  |  |  |  |
|  |  |  | B77 | PE_RX3_DR11_n |  |  |  |  | 2635.88 | OK |  | OK |  | OK |  | OK |  | OK |  | 2635.88 | OK | OK |  |  |
|  |  |  | B78 | PE_RX3_DR11_p |  |  |  |  | 2636.62 |  |  |  |  |  |  |  |  |  |  | 2636.62 |  |  |  |  |
|  |  |  | B81 | PE_RX4_DR11_n |  |  |  |  | 2959.34 | OK |  | OK |  | OK |  | OK |  | OK |  | 2959.34 |  | OK |  |  |
|  |  |  | B82 | PE_RX4_DR11_p |  |  |  |  | 2960.07 |  |  |  |  |  |  |  |  |  |  | 2960.07 |  |  |  |  |
|  |  |  | B85 | PE_RX1_DR6_n |  |  |  |  | 1778.96 | OK |  | OK |  | OK |  | OK |  | OK |  | 1778.96 | OK | OK | OK |  |
|  |  |  | B86 | PE_RX1_DR6_p |  |  |  |  | 1778.93 |  |  |  |  |  |  |  |  |  |  | 1778.93 |  |  |  |  |
|  |  |  | B89 | PE_RX2_DR6_n |  |  |  |  | 2316.02 | OK |  | OK |  | OK |  | OK |  | OK |  | 2316.02 |  | OK |  |  |
|  |  |  | B90 | PE_RX2_DR6_p |  |  |  |  | 2316.0300000000002 |  |  |  |  |  |  |  |  |  |  | 2316.0300000000002 |  |  |  |  |
|  |  |  | B93 | PE_RX3_DR6_n |  |  |  |  | 2268.5700000000002 | OK |  | OK |  | OK |  | OK |  | OK |  | 2268.5700000000002 | OK | OK |  |  |
|  |  |  | B94 | PE_RX3_DR6_p |  |  |  |  | 2268.5500000000002 |  |  |  |  |  |  |  |  |  |  | 2268.5500000000002 |  |  |  |  |
|  |  |  | B97 | PE_RX4_DR6_n |  |  |  |  | 2203.2800000000002 | OK |  | OK |  | OK |  | OK |  | OK |  | 2203.2800000000002 |  | OK |  |  |
|  |  |  | B98 | PE_RX4_DR6_p |  |  |  |  | 2203.2800000000002 |  |  |  |  |  |  |  |  |  |  | 2203.2800000000002 |  |  |  |  |
|  |  | 3_J19 | B4 | PE_RX1_DR14_n |  |  |  |  | 5517.26 | OK |  | OK |  | OK |  | OK |  | OK |  | 5517.26 | OK | OK | OK |  |
|  |  |  | B5 | PE_RX1_DR14_p |  |  |  |  | 5517.79 |  |  |  |  |  |  |  |  |  |  | 5517.79 |  |  |  |  |
|  |  |  | B8 | PE_RX2_DR14_n |  |  |  |  | 6084.91 | OK |  | OK |  | OK |  | OK |  | OK |  | 6084.91 |  | OK |  |  |
|  |  |  | B9 | PE_RX2_DR14_p |  |  |  |  | 6085.23 |  |  |  |  |  |  |  |  |  |  | 6085.23 |  |  |  |  |
|  |  |  | B12 | PE_RX3_DR14_n |  |  |  |  | 6470.1 | OK |  | OK |  | OK |  | OK |  | OK |  | 6470.1 | OK | OK |  |  |
|  |  |  | B13 | PE_RX3_DR14_p |  |  |  |  | 6469.99 |  |  |  |  |  |  |  |  |  |  | 6469.99 |  |  |  |  |
|  |  |  | B16 | PE_RX4_DR14_n |  |  |  |  | 6775.55 | OK |  | OK |  | OK |  | OK |  | OK |  | 6775.55 |  | OK |  |  |
|  |  |  | B17 | PE_RX4_DR14_p |  |  |  |  | 6775.84 |  |  |  |  |  |  |  |  |  |  | 6775.84 |  |  |  |  |
|  |  |  | B20 | PE_RX1_DR13_n |  |  |  |  | 2600.88 | OK |  | OK |  | OK |  | OK |  | OK |  | 2600.88 | OK | OK | OK |  |
|  |  |  | B21 | PE_RX1_DR13_p |  |  |  |  | 2600.6 |  |  |  |  |  |  |  |  |  |  | 2600.6 |  |  |  |  |
|  |  |  | B24 | PE_RX2_DR13_n |  |  |  |  | 2889.56 | OK |  | OK |  | OK |  | OK |  | OK |  | 2889.56 |  | OK |  |  |
|  |  |  | B25 | PE_RX2_DR13_p |  |  |  |  | 2890.27 |  |  |  |  |  |  |  |  |  |  | 2890.27 |  |  |  |  |
|  |  |  | B28 | PE_RX3_DR13_n |  |  |  |  | 3194.59 | OK |  | OK |  | OK |  | OK |  | OK |  | 3194.59 | OK | OK |  |  |
|  |  |  | B29 | PE_RX3_DR13_p |  |  |  |  | 3195.06 |  |  |  |  |  |  |  |  |  |  | 3195.06 |  |  |  |  |
|  |  |  | B32 | PE_RX4_DR13_n |  |  |  |  | 3489.03 | OK |  | OK |  | OK |  | OK |  | OK |  | 3489.03 |  | OK |  |  |
|  |  |  | B33 | PE_RX4_DR13_p |  |  |  |  | 3489.49 |  |  |  |  |  |  |  |  |  |  | 3489.49 |  |  |  |  |
|  |  |  | B36 | PE_RX1_DR9_n |  |  |  |  | 6704.35 | OK |  | OK |  | OK |  | OK |  | OK |  | 6704.35 | OK | OK | OK |  |
|  |  |  | B37 | PE_RX1_DR9_p |  |  |  |  | 6704.35 |  |  |  |  |  |  |  |  |  |  | 6704.35 |  |  |  |  |
|  |  |  | B40 | PE_RX2_DR9_n |  |  |  |  | 6387.53 | OK |  | OK |  | OK |  | OK |  | OK |  | 6387.53 |  | OK |  |  |
|  |  |  | B41 | PE_RX2_DR9_p |  |  |  |  | 6387.51 |  |  |  |  |  |  |  |  |  |  | 6387.51 |  |  |  |  |
|  |  |  | B46 | PE_RX3_DR9_n |  |  |  |  | 6418.17 | OK |  | OK |  | OK |  | OK |  | OK |  | 6418.17 | OK | OK |  |  |
|  |  |  | B47 | PE_RX3_DR9_p |  |  |  |  | 6418.43 |  |  |  |  |  |  |  |  |  |  | 6418.43 |  |  |  |  |
|  |  |  | B50 | PE_RX4_DR9_n |  |  |  |  | 6379.88 | OK |  | OK |  | OK |  | OK |  | OK |  | 6379.88 |  | OK |  |  |
|  |  |  | B51 | PE_RX4_DR9_p |  |  |  |  | 6380.04 |  |  |  |  |  |  |  |  |  |  | 6380.04 |  |  |  |  |
|  |  |  | B57 | PE_RX1_DR8_n |  |  |  |  | 2388.19 | OK |  | OK |  | OK |  | OK |  | OK |  | 2388.19 | OK | OK | OK |  |
|  |  |  | B58 | PE_RX1_DR8_p |  |  |  |  | 2388.17 |  |  |  |  |  |  |  |  |  |  | 2388.17 |  |  |  |  |
|  |  |  | B61 | PE_RX2_DR8_n |  |  |  |  | 2061.2600000000002 | OK |  | OK |  | OK |  | OK |  | OK |  | 2061.2600000000002 |  | OK |  |  |
|  |  |  | B62 | PE_RX2_DR8_p |  |  |  |  | 2061.23 |  |  |  |  |  |  |  |  |  |  | 2061.23 |  |  |  |  |
|  |  |  | B65 | PE_RX3_DR8_n |  |  |  |  | 2036.12 | OK |  | OK |  | OK |  | OK |  | OK |  | 2036.12 | OK | OK |  |  |
|  |  |  | B66 | PE_RX3_DR8_p |  |  |  |  | 2036.08 |  |  |  |  |  |  |  |  |  |  | 2036.08 |  |  |  |  |
|  |  |  | B69 | PE_RX4_DR8_n |  |  |  |  | 2002.18 | OK |  | OK |  | OK |  | OK |  | OK |  | 2002.18 |  | OK |  |  |
|  |  |  | B70 | PE_RX4_DR8_p |  |  |  |  | 2002.05 |  |  |  |  |  |  |  |  |  |  | 2002.05 |  |  |  |  |
|  |  |  | B73 | PE_RX1_DR12_n |  |  |  |  | 3918.81 | OK |  | OK |  | OK |  | OK |  | OK |  | 3918.81 | OK | OK | OK |  |
|  |  |  | B74 | PE_RX1_DR12_p |  |  |  |  | 3918.02 |  |  |  |  |  |  |  |  |  |  | 3918.02 |  |  |  |  |
|  |  |  | B77 | PE_RX2_DR12_n |  |  |  |  | 3521.23 | OK |  | OK |  | OK |  | OK |  | OK |  | 3521.23 |  | OK |  |  |
|  |  |  | B78 | PE_RX2_DR12_p |  |  |  |  | 3520.59 |  |  |  |  |  |  |  |  |  |  | 3520.59 |  |  |  |  |
|  |  |  | B81 | PE_RX3_DR12_n |  |  |  |  | 3381.96 | OK |  | OK |  | OK |  | OK |  | OK |  | 3381.96 | OK | OK |  |  |
|  |  |  | B82 | PE_RX3_DR12_p |  |  |  |  | 3381.2 |  |  |  |  |  |  |  |  |  |  | 3381.2 |  |  |  |  |
|  |  |  | B85 | PE_RX4_DR12_n |  |  |  |  | 3270.19 | OK |  | OK |  | OK |  | OK |  | OK |  | 3270.19 |  | OK |  |  |
|  |  |  | B86 | PE_RX4_DR12_p |  |  |  |  | 3269.95 |  |  |  |  |  |  |  |  |  |  | 3269.95 |  |  |  |  |
|  |  |  | B93 | PE_RX1_DR4_n |  |  |  |  | 12577.79 | OK |  | OK |  | OK |  | OK |  | OK |  | 12577.79 | OK | OK | OK | Same group with 2_J18 A2,3,6,7為一群 |
|  |  |  | B94 | PE_RX1_DR4_p |  |  |  |  | 12577.82 |  |  |  |  |  |  |  |  |  |  | 12577.82 |  |  |  |  |
|  |  |  | B97 | PE_RX2_DR4_n |  |  |  |  | 12587.98 | OK |  | OK |  | OK |  | OK |  | OK |  | 12587.98 |  | OK |  |  |
|  |  |  | B98 | PE_RX2_DR4_p |  |  |  |  | 12587.92 |  |  |  |  |  |  |  |  |  |  | 12587.92 |  |  |  |  |
